(kicad_pcb
	(version 20260206)
	(generator "pcbnew")
	(generator_version "10.0")
	(general
		(thickness 1.6)
		(legacy_teardrops no)
	)
	(paper "A4")
	(title_block
		(title "v1-chassis-manager — T6M_CM_d_v01_1031_1645.brd")
		(comment 1 "Open CloudServer (Microsoft) / footprints 805-814 of 2512")
	)
	(layers
		(0 "F.Cu" signal "TOP")
		(4 "In1.Cu" signal "GND1")
		(6 "In2.Cu" signal "IN1")
		(8 "In3.Cu" signal "VCC1")
		(10 "In4.Cu" signal "VCC2")
		(12 "In5.Cu" signal "GND2")
		(14 "In6.Cu" signal "IN2")
		(16 "In7.Cu" signal "IN3")
		(18 "In8.Cu" signal "GND3")
		(2 "B.Cu" signal "BOTTOM")
		(9 "F.Adhes" user "F.Adhesive")
		(11 "B.Adhes" user "B.Adhesive")
		(13 "F.Paste" user "Package Geometry/Pastemask Top")
		(15 "B.Paste" user "Package Geometry/Pastemask Bottom")
		(5 "F.SilkS" user "Ref Des/Silkscreen Top")
		(7 "B.SilkS" user "Ref Des/Silkscreen Bottom")
		(1 "F.Mask" user "Board Geometry/Soldermask Top")
		(3 "B.Mask" user "Board Geometry/Soldermask Bottom")
		(17 "Dwgs.User" user "User.Drawings")
		(19 "Cmts.User" user "User.Comments")
		(21 "Eco1.User" user "User.Eco1")
		(23 "Eco2.User" user "User.Eco2")
		(25 "Edge.Cuts" user "Board Geometry/Outline")
		(27 "Margin" user)
		(31 "F.CrtYd" user "Package Geometry/Place Bound Top")
		(29 "B.CrtYd" user "Package Geometry/Place Bound Bottom")
		(35 "F.Fab" user "Ref Des/Assembly Top")
		(33 "B.Fab" user "Ref Des/Assembly Bottom")
	)
	(footprint ""
		(layer "F.Cu")
		(at 94.211394 -188.838586)
		(property "Reference" "R939"
			(at -1.182878 -7.467346 0)
			(unlocked yes)
			(layer "F.SilkS")
			(effects
				(font
					(size 0.7874 0.5842)
					(thickness 0.1524)
				)
				(justify left)
			)
		)
		(property "Value" ""
			(at 0 0 0)
			(layer "F.Fab")
			(effects
				(font
					(size 1.27 1.27)
				)
			)
		)
		(duplicate_pad_numbers_are_jumpers no)
		(fp_line
			(start -0.7874 -0.4064)
			(end 0.7874 -0.4064)
			(stroke
				(width 0.1524)
				(type default)
			)
			(layer "F.SilkS")
		)
		(fp_line
			(start -0.7874 0.4064)
			(end -0.7874 -0.4064)
			(stroke
				(width 0.1524)
				(type default)
			)
			(layer "F.SilkS")
		)
		(fp_line
			(start 0.7874 -0.4064)
			(end 0.7874 0.4064)
			(stroke
				(width 0.1524)
				(type default)
			)
			(layer "F.SilkS")
		)
		(fp_line
			(start 0.7874 0.4064)
			(end -0.7874 0.4064)
			(stroke
				(width 0.1524)
				(type default)
			)
			(layer "F.SilkS")
		)
		(fp_poly
			(pts
				(xy -0.508 0.2794) (xy -0.508 0.2286) (xy -0.635 0.2286) (xy -0.635 -0.254) (xy -0.5334 -0.254)
				(xy -0.5334 -0.2794) (xy 0.5334 -0.2794) (xy 0.5334 -0.254) (xy 0.635 -0.254) (xy 0.635 0.254) (xy 0.5334 0.254)
				(xy 0.5334 0.2794)
			)
			(stroke
				(width 0)
				(type default)
			)
			(fill no)
			(layer "F.CrtYd")
		)
		(pad "1" smd rect
			(at 0.40005 0)
			(size 0.4572 0.508)
			(layers "F.Cu" "F.Mask" "F.Paste")
			(net "UART_T6_NODE2_RXD")
		)
		(pad "2" smd rect
			(at -0.40005 0)
			(size 0.4572 0.508)
			(layers "F.Cu" "F.Mask" "F.Paste")
			(net "UART_T6_NODE2_RXD_R")
		)
	)
	(footprint ""
		(layer "F.Cu")
		(at 18.226532 -56.004206 -90)
		(property "Reference" "R642"
			(at 2.070608 -13.912088 90)
			(unlocked yes)
			(layer "F.SilkS")
			(effects
				(font
					(size 0.7874 0.5842)
					(thickness 0.1524)
				)
				(justify left)
			)
		)
		(property "Value" ""
			(at 0 0 270)
			(layer "F.Fab")
			(effects
				(font
					(size 1.27 1.27)
				)
			)
		)
		(duplicate_pad_numbers_are_jumpers no)
		(fp_line
			(start -0.7874 0.4064)
			(end -0.7874 -0.4064)
			(stroke
				(width 0.1524)
				(type default)
			)
			(layer "F.SilkS")
		)
		(fp_line
			(start 0.7874 0.4064)
			(end -0.7874 0.4064)
			(stroke
				(width 0.1524)
				(type default)
			)
			(layer "F.SilkS")
		)
		(fp_line
			(start -0.7874 -0.4064)
			(end 0.7874 -0.4064)
			(stroke
				(width 0.1524)
				(type default)
			)
			(layer "F.SilkS")
		)
		(fp_line
			(start 0.7874 -0.4064)
			(end 0.7874 0.4064)
			(stroke
				(width 0.1524)
				(type default)
			)
			(layer "F.SilkS")
		)
		(fp_poly
			(pts
				(xy -0.508 0.2794) (xy -0.508 0.2286) (xy -0.635 0.2286) (xy -0.635 -0.254) (xy -0.5334 -0.254)
				(xy -0.5334 -0.2794) (xy 0.5334 -0.2794) (xy 0.5334 -0.254) (xy 0.635 -0.254) (xy 0.635 0.254) (xy 0.5334 0.254)
				(xy 0.5334 0.2794)
			)
			(stroke
				(width 0)
				(type default)
			)
			(fill no)
			(layer "F.CrtYd")
		)
		(pad "1" smd rect
			(at 0.40005 0 270)
			(size 0.4572 0.508)
			(layers "F.Cu" "F.Mask" "F.Paste")
			(net "CRT_B_L")
		)
		(pad "2" smd rect
			(at -0.40005 0 270)
			(size 0.4572 0.508)
			(layers "F.Cu" "F.Mask" "F.Paste")
			(net "GND")
		)
	)
	(footprint ""
		(layer "F.Cu")
		(at 120.38076 -179.363624 -90)
		(property "Reference" "D16"
			(at -3.37693 -6.62305 90)
			(unlocked yes)
			(layer "F.SilkS")
			(effects
				(font
					(size 0.635 0.4064)
					(thickness 0.1524)
				)
				(justify left)
			)
		)
		(property "Value" ""
			(at 0 0 270)
			(layer "F.Fab")
			(effects
				(font
					(size 1.27 1.27)
				)
			)
		)
		(duplicate_pad_numbers_are_jumpers no)
		(fp_line
			(start -1.3208 0.5588)
			(end -1.3208 -0.5588)
			(stroke
				(width 0.1524)
				(type default)
			)
			(layer "F.SilkS")
		)
		(fp_line
			(start 1.3208 0.5588)
			(end -1.3208 0.5588)
			(stroke
				(width 0.1524)
				(type default)
			)
			(layer "F.SilkS")
		)
		(fp_line
			(start 1.6256 0.5588)
			(end 1.6256 -0.5588)
			(stroke
				(width 0.1524)
				(type default)
			)
			(layer "F.SilkS")
		)
		(fp_line
			(start 1.778 0.5588)
			(end 1.3208 0.5588)
			(stroke
				(width 0.1524)
				(type default)
			)
			(layer "F.SilkS")
		)
		(fp_line
			(start -1.3208 -0.5588)
			(end 1.3208 -0.5588)
			(stroke
				(width 0.1524)
				(type default)
			)
			(layer "F.SilkS")
		)
		(fp_line
			(start 1.3208 -0.5588)
			(end 1.3208 0.5588)
			(stroke
				(width 0.1524)
				(type default)
			)
			(layer "F.SilkS")
		)
		(fp_line
			(start 1.4732 -0.5588)
			(end 1.4732 0.5588)
			(stroke
				(width 0.1524)
				(type default)
			)
			(layer "F.SilkS")
		)
		(fp_line
			(start 1.778 -0.5588)
			(end 1.778 0.5588)
			(stroke
				(width 0.1524)
				(type default)
			)
			(layer "F.SilkS")
		)
		(fp_line
			(start 1.778 -0.5588)
			(end 1.3208 -0.5588)
			(stroke
				(width 0.1524)
				(type default)
			)
			(layer "F.SilkS")
		)
		(fp_rect
			(start -1.1684 0.508)
			(end 1.1684 -0.508)
			(stroke
				(width 0)
				(type default)
			)
			(fill no)
			(layer "F.CrtYd")
		)
		(pad "A" smd rect
			(at -0.750062 0 270)
			(size 0.8128 0.8128)
			(layers "F.Cu" "F.Mask" "F.Paste")
			(net "UART_SW_S1_N")
		)
		(pad "C" smd rect
			(at 0.750062 0 270)
			(size 0.8128 0.8128)
			(layers "F.Cu" "F.Mask" "F.Paste")
			(net "N31328108")
		)
	)
	(footprint ""
		(layer "F.Cu")
		(at 52.81676 -185.205624 90)
		(property "Reference" "R831"
			(at 4.006088 0.055372 90)
			(unlocked yes)
			(layer "F.SilkS")
			(effects
				(font
					(size 0.7874 0.5842)
					(thickness 0.1524)
				)
				(justify left)
			)
		)
		(property "Value" ""
			(at 0 0 90)
			(layer "F.Fab")
			(effects
				(font
					(size 1.27 1.27)
				)
			)
		)
		(duplicate_pad_numbers_are_jumpers no)
		(fp_line
			(start 0.7874 -0.4064)
			(end 0.7874 0.4064)
			(stroke
				(width 0.1524)
				(type default)
			)
			(layer "F.SilkS")
		)
		(fp_line
			(start -0.7874 -0.4064)
			(end 0.7874 -0.4064)
			(stroke
				(width 0.1524)
				(type default)
			)
			(layer "F.SilkS")
		)
		(fp_line
			(start 0.7874 0.4064)
			(end -0.7874 0.4064)
			(stroke
				(width 0.1524)
				(type default)
			)
			(layer "F.SilkS")
		)
		(fp_line
			(start -0.7874 0.4064)
			(end -0.7874 -0.4064)
			(stroke
				(width 0.1524)
				(type default)
			)
			(layer "F.SilkS")
		)
		(fp_poly
			(pts
				(xy -0.508 0.2794) (xy -0.508 0.2286) (xy -0.635 0.2286) (xy -0.635 -0.254) (xy -0.5334 -0.254)
				(xy -0.5334 -0.2794) (xy 0.5334 -0.2794) (xy 0.5334 -0.254) (xy 0.635 -0.254) (xy 0.635 0.254) (xy 0.5334 0.254)
				(xy 0.5334 0.2794)
			)
			(stroke
				(width 0)
				(type default)
			)
			(fill no)
			(layer "F.CrtYd")
		)
		(pad "1" smd rect
			(at 0.40005 0 90)
			(size 0.4572 0.508)
			(layers "F.Cu" "F.Mask" "F.Paste")
			(net "PSU1_AC_OK_R")
		)
		(pad "2" smd rect
			(at -0.40005 0 90)
			(size 0.4572 0.508)
			(layers "F.Cu" "F.Mask" "F.Paste")
			(net "PSU1_AC_OK")
		)
	)
	(footprint ""
		(layer "F.Cu")
		(at 82.340196 -108.09859 180)
		(property "Reference" "R1100"
			(at 5.41147 0.60198 0)
			(unlocked yes)
			(layer "F.SilkS")
			(effects
				(font
					(size 0.7874 0.5842)
					(thickness 0.1524)
				)
				(justify left)
			)
		)
		(property "Value" ""
			(at 0 0 180)
			(layer "F.Fab")
			(effects
				(font
					(size 1.27 1.27)
				)
			)
		)
		(duplicate_pad_numbers_are_jumpers no)
		(fp_line
			(start 0.7874 0.4064)
			(end -0.7874 0.4064)
			(stroke
				(width 0.1524)
				(type default)
			)
			(layer "F.SilkS")
		)
		(fp_line
			(start 0.7874 -0.4064)
			(end 0.7874 0.4064)
			(stroke
				(width 0.1524)
				(type default)
			)
			(layer "F.SilkS")
		)
		(fp_line
			(start -0.7874 0.4064)
			(end -0.7874 -0.4064)
			(stroke
				(width 0.1524)
				(type default)
			)
			(layer "F.SilkS")
		)
		(fp_line
			(start -0.7874 -0.4064)
			(end 0.7874 -0.4064)
			(stroke
				(width 0.1524)
				(type default)
			)
			(layer "F.SilkS")
		)
		(fp_poly
			(pts
				(xy -0.508 0.2794) (xy -0.508 0.2286) (xy -0.635 0.2286) (xy -0.635 -0.254) (xy -0.5334 -0.254)
				(xy -0.5334 -0.2794) (xy 0.5334 -0.2794) (xy 0.5334 -0.254) (xy 0.635 -0.254) (xy 0.635 0.254) (xy 0.5334 0.254)
				(xy 0.5334 0.2794)
			)
			(stroke
				(width 0)
				(type default)
			)
			(fill no)
			(layer "F.CrtYd")
		)
		(pad "1" smd rect
			(at 0.40005 0 180)
			(size 0.4572 0.508)
			(layers "F.Cu" "F.Mask" "F.Paste")
			(net "FM_CPLD_NODE1_P3V3_SUS_EN")
		)
		(pad "2" smd rect
			(at -0.40005 0 180)
			(size 0.4572 0.508)
			(layers "F.Cu" "F.Mask" "F.Paste")
			(net "P3V3_STB_NODE1")
		)
	)
	(footprint ""
		(layer "F.Cu")
		(at 27.385772 -103.221282 180)
		(property "Reference" "R1106"
			(at 0.39751 -4.406392 90)
			(unlocked yes)
			(layer "F.SilkS")
			(effects
				(font
					(size 0.7874 0.5842)
					(thickness 0.1524)
				)
				(justify left)
			)
		)
		(property "Value" ""
			(at 0 0 180)
			(layer "F.Fab")
			(effects
				(font
					(size 1.27 1.27)
				)
			)
		)
		(duplicate_pad_numbers_are_jumpers no)
		(fp_line
			(start 0.7874 0.4064)
			(end -0.7874 0.4064)
			(stroke
				(width 0.1524)
				(type default)
			)
			(layer "F.SilkS")
		)
		(fp_line
			(start 0.7874 -0.4064)
			(end 0.7874 0.4064)
			(stroke
				(width 0.1524)
				(type default)
			)
			(layer "F.SilkS")
		)
		(fp_line
			(start -0.7874 0.4064)
			(end -0.7874 -0.4064)
			(stroke
				(width 0.1524)
				(type default)
			)
			(layer "F.SilkS")
		)
		(fp_line
			(start -0.7874 -0.4064)
			(end 0.7874 -0.4064)
			(stroke
				(width 0.1524)
				(type default)
			)
			(layer "F.SilkS")
		)
		(fp_poly
			(pts
				(xy -0.508 0.2794) (xy -0.508 0.2286) (xy -0.635 0.2286) (xy -0.635 -0.254) (xy -0.5334 -0.254)
				(xy -0.5334 -0.2794) (xy 0.5334 -0.2794) (xy 0.5334 -0.254) (xy 0.635 -0.254) (xy 0.635 0.254) (xy 0.5334 0.254)
				(xy 0.5334 0.2794)
			)
			(stroke
				(width 0)
				(type default)
			)
			(fill no)
			(layer "F.CrtYd")
		)
		(pad "1" smd rect
			(at 0.40005 0 180)
			(size 0.4572 0.508)
			(layers "F.Cu" "F.Mask" "F.Paste")
			(net "GND")
		)
		(pad "2" smd rect
			(at -0.40005 0 180)
			(size 0.4572 0.508)
			(layers "F.Cu" "F.Mask" "F.Paste")
			(net "FM_CPLD_NODE1_P1V5_SUS_EN")
		)
	)
	(footprint ""
		(layer "F.Cu")
		(at 82.53476 -188.126624 90)
		(property "Reference" "C658"
			(at 4.548886 -1.831848 90)
			(unlocked yes)
			(layer "F.SilkS")
			(effects
				(font
					(size 0.7874 0.5842)
					(thickness 0.1524)
				)
				(justify left)
			)
		)
		(property "Value" ""
			(at 0 0 90)
			(layer "F.Fab")
			(effects
				(font
					(size 1.27 1.27)
				)
			)
		)
		(duplicate_pad_numbers_are_jumpers no)
		(fp_line
			(start 0.7874 -0.4064)
			(end 0.7874 0.4064)
			(stroke
				(width 0.1524)
				(type default)
			)
			(layer "F.SilkS")
		)
		(fp_line
			(start -0.7874 -0.4064)
			(end 0.7874 -0.4064)
			(stroke
				(width 0.1524)
				(type default)
			)
			(layer "F.SilkS")
		)
		(fp_line
			(start 0 0.381)
			(end 0 -0.381)
			(stroke
				(width 0.1524)
				(type default)
			)
			(layer "F.SilkS")
		)
		(fp_line
			(start 0.7874 0.4064)
			(end -0.7874 0.4064)
			(stroke
				(width 0.1524)
				(type default)
			)
			(layer "F.SilkS")
		)
		(fp_line
			(start -0.7874 0.4064)
			(end -0.7874 -0.4064)
			(stroke
				(width 0.1524)
				(type default)
			)
			(layer "F.SilkS")
		)
		(fp_poly
			(pts
				(xy -0.5334 0.254) (xy -0.635 0.254) (xy -0.635 0.2286) (xy -0.635 -0.254) (xy -0.5334 -0.254) (xy -0.5334 -0.2794)
				(xy 0.5334 -0.2794) (xy 0.5334 -0.254) (xy 0.635 -0.254) (xy 0.635 0.254) (xy 0.5334 0.254) (xy 0.5334 0.2794)
				(xy -0.508 0.2794) (xy -0.5334 0.2794)
			)
			(stroke
				(width 0)
				(type default)
			)
			(fill no)
			(layer "F.CrtYd")
		)
		(pad "1" smd rect
			(at 0.40005 0 90)
			(size 0.4572 0.508)
			(layers "F.Cu" "F.Mask" "F.Paste")
			(net "T4_NODE1_EN_R")
		)
		(pad "2" smd rect
			(at -0.40005 0 90)
			(size 0.4572 0.508)
			(layers "F.Cu" "F.Mask" "F.Paste")
			(net "GND")
		)
	)
	(footprint ""
		(layer "F.Cu")
		(at 116.31549 -156.330142 180)
		(property "Reference" "U110"
			(at 0.185166 3.018282 90)
			(unlocked yes)
			(layer "F.SilkS")
			(effects
				(font
					(size 0.635 0.4064)
					(thickness 0.1524)
				)
			)
		)
		(property "Value" ""
			(at 0 0 180)
			(layer "F.Fab")
			(effects
				(font
					(size 1.27 1.27)
				)
			)
		)
		(duplicate_pad_numbers_are_jumpers no)
		(fp_line
			(start 1.651 1.905)
			(end -1.651 1.905)
			(stroke
				(width 0.1524)
				(type default)
			)
			(layer "F.SilkS")
		)
		(fp_line
			(start 1.651 -1.905)
			(end 1.651 1.905)
			(stroke
				(width 0.1524)
				(type default)
			)
			(layer "F.SilkS")
		)
		(fp_line
			(start -1.651 1.905)
			(end -1.651 -1.905)
			(stroke
				(width 0.1524)
				(type default)
			)
			(layer "F.SilkS")
		)
		(fp_line
			(start -1.651 -1.905)
			(end 1.651 -1.905)
			(stroke
				(width 0.1524)
				(type default)
			)
			(layer "F.SilkS")
		)
		(fp_poly
			(pts
				(xy -1.524 0.7112) (xy -1.524 1.7526) (xy -0.508 1.7526) (xy -0.508 0.6985) (xy 0.508 0.6985) (xy 0.508 1.7526)
				(xy 1.524 1.7526) (xy 1.524 0.6985) (xy 1.524 -0.6985) (xy 0.508 -0.6985) (xy 0.508 -1.7526) (xy -0.508 -1.7526)
				(xy -0.508 -0.6985) (xy -1.524 -0.6985) (xy -1.524 0.6985)
			)
			(stroke
				(width 0)
				(type default)
			)
			(fill no)
			(layer "F.CrtYd")
		)
		(fp_text user "S"
			(at 1.02997 -0.100584 0)
			(unlocked yes)
			(layer "F.SilkS")
			(effects
				(font
					(size 0.635 0.4064)
					(thickness 0.1524)
				)
			)
		)
		(fp_text user "G"
			(at -0.92075 -0.076708 0)
			(unlocked yes)
			(layer "F.SilkS")
			(effects
				(font
					(size 0.635 0.4064)
					(thickness 0.1524)
				)
			)
		)
		(fp_text user "D"
			(at -1.11125 -1.374394 0)
			(unlocked yes)
			(layer "F.SilkS")
			(effects
				(font
					(size 0.635 0.4064)
					(thickness 0.1524)
				)
			)
		)
		(pad "D" smd rect
			(at 0 -1.1176 180)
			(size 1.016 1.27)
			(layers "F.Cu" "F.Mask" "F.Paste")
			(net "N52998261")
		)
		(pad "G" smd rect
			(at -1.016 1.1176 180)
			(size 1.016 1.27)
			(layers "F.Cu" "F.Mask" "F.Paste")
			(net "POWER_SW3_PWR_CTR_N")
		)
		(pad "S" smd rect
			(at 1.016 1.1176 180)
			(size 1.016 1.27)
			(layers "F.Cu" "F.Mask" "F.Paste")
			(net "GND")
		)
	)
	(footprint ""
		(layer "F.Cu")
		(at 107.652566 -142.394178 90)
		(property "Reference" "PR73"
			(at 1.927352 0.092964 90)
			(unlocked yes)
			(layer "F.SilkS")
			(effects
				(font
					(size 0.635 0.4064)
					(thickness 0.1524)
				)
				(justify left)
			)
		)
		(property "Value" ""
			(at 0 0 90)
			(layer "F.Fab")
			(effects
				(font
					(size 1.27 1.27)
				)
			)
		)
		(duplicate_pad_numbers_are_jumpers no)
		(fp_line
			(start 0.7874 -0.4064)
			(end 0.7874 0.4064)
			(stroke
				(width 0.1524)
				(type default)
			)
			(layer "F.SilkS")
		)
		(fp_line
			(start -0.7874 -0.4064)
			(end 0.7874 -0.4064)
			(stroke
				(width 0.1524)
				(type default)
			)
			(layer "F.SilkS")
		)
		(fp_line
			(start 0.7874 0.4064)
			(end -0.7874 0.4064)
			(stroke
				(width 0.1524)
				(type default)
			)
			(layer "F.SilkS")
		)
		(fp_line
			(start -0.7874 0.4064)
			(end -0.7874 -0.4064)
			(stroke
				(width 0.1524)
				(type default)
			)
			(layer "F.SilkS")
		)
		(fp_poly
			(pts
				(xy -0.508 0.2794) (xy -0.508 0.2286) (xy -0.635 0.2286) (xy -0.635 -0.254) (xy -0.5334 -0.254)
				(xy -0.5334 -0.2794) (xy 0.5334 -0.2794) (xy 0.5334 -0.254) (xy 0.635 -0.254) (xy 0.635 0.254) (xy 0.5334 0.254)
				(xy 0.5334 0.2794)
			)
			(stroke
				(width 0)
				(type default)
			)
			(fill no)
			(layer "F.CrtYd")
		)
		(pad "1" smd rect
			(at 0.40005 0 90)
			(size 0.4572 0.508)
			(layers "F.Cu" "F.Mask" "F.Paste")
			(net "VR_PVCCP_NODE1_TSEN_R")
		)
		(pad "2" smd rect
			(at -0.40005 0 90)
			(size 0.4572 0.508)
			(layers "F.Cu" "F.Mask" "F.Paste")
			(net "VR_PVCCP_NODE1_TSEN")
		)
	)
	(footprint ""
		(layer "F.Cu")
		(at 50.53076 -182.246524 90)
		(property "Reference" "C605"
			(at -133.313932 -3.637788 90)
			(unlocked yes)
			(layer "F.SilkS")
			(effects
				(font
					(size 0.7874 0.5842)
					(thickness 0.1524)
				)
				(justify left)
			)
		)
		(property "Value" ""
			(at 0 0 90)
			(layer "F.Fab")
			(effects
				(font
					(size 1.27 1.27)
				)
			)
		)
		(duplicate_pad_numbers_are_jumpers no)
		(fp_line
			(start 0.7874 -0.4064)
			(end 0.7874 0.4064)
			(stroke
				(width 0.1524)
				(type default)
			)
			(layer "F.SilkS")
		)
		(fp_line
			(start -0.7874 -0.4064)
			(end 0.7874 -0.4064)
			(stroke
				(width 0.1524)
				(type default)
			)
			(layer "F.SilkS")
		)
		(fp_line
			(start 0 0.381)
			(end 0 -0.381)
			(stroke
				(width 0.1524)
				(type default)
			)
			(layer "F.SilkS")
		)
		(fp_line
			(start 0.7874 0.4064)
			(end -0.7874 0.4064)
			(stroke
				(width 0.1524)
				(type default)
			)
			(layer "F.SilkS")
		)
		(fp_line
			(start -0.7874 0.4064)
			(end -0.7874 -0.4064)
			(stroke
				(width 0.1524)
				(type default)
			)
			(layer "F.SilkS")
		)
		(fp_poly
			(pts
				(xy -0.5334 0.254) (xy -0.635 0.254) (xy -0.635 0.2286) (xy -0.635 -0.254) (xy -0.5334 -0.254) (xy -0.5334 -0.2794)
				(xy 0.5334 -0.2794) (xy 0.5334 -0.254) (xy 0.635 -0.254) (xy 0.635 0.254) (xy 0.5334 0.254) (xy 0.5334 0.2794)
				(xy -0.508 0.2794) (xy -0.5334 0.2794)
			)
			(stroke
				(width 0)
				(type default)
			)
			(fill no)
			(layer "F.CrtYd")
		)
		(pad "1" smd rect
			(at 0.40005 0 90)
			(size 0.4572 0.508)
			(layers "F.Cu" "F.Mask" "F.Paste")
			(net "PSU3_AC_OK")
		)
		(pad "2" smd rect
			(at -0.40005 0 90)
			(size 0.4572 0.508)
			(layers "F.Cu" "F.Mask" "F.Paste")
			(net "GND")
		)
	)
)
